# T6G (Grand Teton) — schematic netlist excerpt (pin names and nets, part order shuffled) for the footprints in the layout excerpt that follows; sources: Cadence DE-HDL packaged netlist, KiCad conversion of 04192023_DAF0TMB3IC0_F0TG_MB_C_brd_V02_OCP.brd

R3483  Q_RES  33.2 1% CHIP  pkg 0402LF  page 81 : A = GPU_FPGA_EROT_RECOV_N ; B = GPU_FPGA_EROT_RECOV_R_N

(kicad_pcb
	(version 20260206)
	(generator "pcbnew")
	(generator_version "10.0")
	(general
		(thickness 1.6)
		(legacy_teardrops no)
	)
	(paper "A4")
	(title_block
		(title "04192023_DAF0TMB3IC0_F0TG_MB_C_brd_V02_OCP.brd")
		(comment 1 "Grand Teton / footprints 2862-2862 of 8354")
	)
	(layers
		(0 "F.Cu" signal "TOP")
		(4 "In1.Cu" signal "GND")
		(6 "In2.Cu" signal "IN1")
		(8 "In3.Cu" signal "GND1")
		(10 "In4.Cu" signal "IN2")
		(12 "In5.Cu" signal "GND2")
		(14 "In6.Cu" signal "IN3")
		(16 "In7.Cu" signal "GND3")
		(18 "In8.Cu" signal "VCC")
		(20 "In9.Cu" signal "VCC1")
		(22 "In10.Cu" signal "GND4")
		(24 "In11.Cu" signal "IN4")
		(26 "In12.Cu" signal "GND5")
		(28 "In13.Cu" signal "IN5")
		(30 "In14.Cu" signal "GND6")
		(32 "In15.Cu" signal "IN6")
		(34 "In16.Cu" signal "GND7")
		(2 "B.Cu" signal "BOTTOM")
		(9 "F.Adhes" user "F.Adhesive")
		(11 "B.Adhes" user "B.Adhesive")
		(13 "F.Paste" user "Package Geometry/Pastemask Top")
		(15 "B.Paste" user "Package Geometry/Pastemask Bottom")
		(5 "F.SilkS" user "Ref Des/Silkscreen Top")
		(7 "B.SilkS" user "Ref Des/Silkscreen Bottom")
		(1 "F.Mask" user "Board Geometry/Soldermask Top")
		(3 "B.Mask" user "Board Geometry/Soldermask Bottom")
		(17 "Dwgs.User" user "User.Drawings")
		(19 "Cmts.User" user "User.Comments")
		(21 "Eco1.User" user "User.Eco1")
		(23 "Eco2.User" user "User.Eco2")
		(25 "Edge.Cuts" user "Board Geometry/Outline")
		(27 "Margin" user)
		(31 "F.CrtYd" user "Package Geometry/Place Bound Top")
		(29 "B.CrtYd" user "Package Geometry/Place Bound Bottom")
		(35 "F.Fab" user "Ref Des/Assembly Top")
		(33 "B.Fab" user "Ref Des/Assembly Bottom")
	)
	(footprint ""
		(layer "F.Cu")
		(at 205.234286 -110.649512 180)
		(property "Reference" "R3483"
			(at 0 0 180)
			(layer "F.SilkS")
			(hide yes)
			(effects
				(font
					(size 1.27 1.27)
				)
			)
		)
		(property "Value" ""
			(at 0 0 180)
			(layer "F.Fab")
			(effects
				(font
					(size 1.27 1.27)
				)
			)
		)
		(duplicate_pad_numbers_are_jumpers no)
		(fp_line
			(start 0.7874 0.4064)
			(end -0.7874 0.4064)
			(stroke
				(width 0.1524)
				(type default)
			)
			(layer "F.SilkS")
		)
		(fp_line
			(start 0.7874 -0.4064)
			(end 0.7874 0.4064)
			(stroke
				(width 0.1524)
				(type default)
			)
			(layer "F.SilkS")
		)
		(fp_line
			(start -0.7874 0.4064)
			(end -0.7874 -0.4064)
			(stroke
				(width 0.1524)
				(type default)
			)
			(layer "F.SilkS")
		)
		(fp_line
			(start -0.7874 -0.4064)
			(end 0.7874 -0.4064)
			(stroke
				(width 0.1524)
				(type default)
			)
			(layer "F.SilkS")
		)
		(fp_line
			(start 0.67945 0.3048)
			(end 0.120396 0.3048)
			(stroke
				(width 0.1)
				(type default)
			)
			(layer "F.Fab")
		)
		(fp_line
			(start 0.67945 -0.3048)
			(end 0.67945 0.3048)
			(stroke
				(width 0.1)
				(type default)
			)
			(layer "F.Fab")
		)
		(fp_line
			(start 0.12065 -0.2794)
			(end 0.12065 -0.3048)
			(stroke
				(width 0.1)
				(type default)
			)
			(layer "F.Fab")
		)
		(fp_line
			(start 0.12065 -0.3048)
			(end 0.67945 -0.3048)
			(stroke
				(width 0.1)
				(type default)
			)
			(layer "F.Fab")
		)
		(fp_line
			(start 0.120396 0.3048)
			(end 0.120396 0.2794)
			(stroke
				(width 0.1)
				(type default)
			)
			(layer "F.Fab")
		)
		(fp_line
			(start 0.120396 0.2794)
			(end -0.12065 0.2794)
			(stroke
				(width 0.1)
				(type default)
			)
			(layer "F.Fab")
		)
		(fp_line
			(start -0.12065 0.3048)
			(end -0.67945 0.3048)
			(stroke
				(width 0.1)
				(type default)
			)
			(layer "F.Fab")
		)
		(fp_line
			(start -0.12065 0.2794)
			(end -0.12065 0.3048)
			(stroke
				(width 0.1)
				(type default)
			)
			(layer "F.Fab")
		)
		(fp_line
			(start -0.12065 -0.2794)
			(end 0.12065 -0.2794)
			(stroke
				(width 0.1)
				(type default)
			)
			(layer "F.Fab")
		)
		(fp_line
			(start -0.12065 -0.305054)
			(end -0.12065 -0.2794)
			(stroke
				(width 0.1)
				(type default)
			)
			(layer "F.Fab")
		)
		(fp_line
			(start -0.67945 0.3048)
			(end -0.67945 -0.305054)
			(stroke
				(width 0.1)
				(type default)
			)
			(layer "F.Fab")
		)
		(fp_line
			(start -0.67945 -0.305054)
			(end -0.12065 -0.305054)
			(stroke
				(width 0.1)
				(type default)
			)
			(layer "F.Fab")
		)
		(pad "1" smd circle
			(at -0.40005 0 180)
			(size 0 0)
			(layers "F.Cu" "F.Mask" "F.Paste")
			(net "GPU_FPGA_EROT_RECOV_N")
		)
		(pad "2" smd circle
			(at 0.40005 0 180)
			(size 0 0)
			(layers "F.Cu" "F.Mask" "F.Paste")
			(net "GPU_FPGA_EROT_RECOV_R_N")
		)
	)
)
